(kicad_pcb
	(version 20260206)
	(generator "pcbnew")
	(generator_version "10.0")
	(general
		(thickness 1.6)
		(legacy_teardrops no)
	)
	(paper "A4")
	(title_block
		(title "Bryce Canyon_R.DPB_16317-1_OCP.brd")
		(comment 1 "Bryce Canyon / footprints 8-14 of 2099")
	)
	(layers
		(0 "F.Cu" signal "TOP")
		(4 "In1.Cu" signal "L2GND")
		(6 "In2.Cu" signal "L3")
		(8 "In3.Cu" signal "L4VCC")
		(10 "In4.Cu" signal "L5VCC")
		(12 "In5.Cu" signal "L6")
		(14 "In6.Cu" signal "L7GND")
		(2 "B.Cu" signal "BOTTOM")
		(9 "F.Adhes" user "F.Adhesive")
		(11 "B.Adhes" user "B.Adhesive")
		(13 "F.Paste" user "Package Geometry/Pastemask Top")
		(15 "B.Paste" user "Package Geometry/Pastemask Bottom")
		(5 "F.SilkS" user "Ref Des/Silkscreen Top")
		(7 "B.SilkS" user "Ref Des/Silkscreen Bottom")
		(1 "F.Mask" user "Board Geometry/Soldermask Top")
		(3 "B.Mask" user "Board Geometry/Soldermask Bottom")
		(17 "Dwgs.User" user "User.Drawings")
		(19 "Cmts.User" user "User.Comments")
		(21 "Eco1.User" user "User.Eco1")
		(23 "Eco2.User" user "User.Eco2")
		(25 "Edge.Cuts" user "Board Geometry/Outline")
		(27 "Margin" user)
		(31 "F.CrtYd" user "Package Geometry/Place Bound Top")
		(29 "B.CrtYd" user "Package Geometry/Place Bound Bottom")
		(35 "F.Fab" user "Ref Des/Assembly Top")
		(33 "B.Fab" user "Ref Des/Assembly Bottom")
	)
	(footprint ""
		(layer "F.Cu")
		(at 462.915 -263.017)
		(property "Reference" "Q40"
			(at 0 0 0)
			(layer "F.SilkS")
			(hide yes)
			(effects
				(font
					(size 1.27 1.27)
				)
			)
		)
		(property "Value" "AO4407AL-GP"
			(at -3.707384 -1.5367 0)
			(unlocked yes)
			(layer "F.Fab")
			(hide yes)
			(effects
				(font
					(size 1.016 1.016)
					(thickness 0.1524)
				)
			)
		)
		(property "Device Type" "SOIC8H69"
			(at -3.707384 -3.0607 0)
			(unlocked yes)
			(layer "F.Fab")
			(hide yes)
			(effects
				(font
					(size 1.016 1.016)
					(thickness 0.1524)
				)
			)
		)
		(duplicate_pad_numbers_are_jumpers no)
		(fp_line
			(start -2.7432 -1.4224)
			(end -2.7432 1.4224)
			(stroke
				(width 0.1524)
				(type default)
			)
			(layer "F.SilkS")
		)
		(fp_line
			(start -2.7432 1.4224)
			(end -2.6416 1.4224)
			(stroke
				(width 0.1524)
				(type default)
			)
			(layer "F.SilkS")
		)
		(fp_line
			(start -2.7432 1.4224)
			(end 2.1336 1.4224)
			(stroke
				(width 0.1524)
				(type default)
			)
			(layer "F.SilkS")
		)
		(fp_line
			(start -2.7178 -0.508)
			(end -2.1844 -0.0508)
			(stroke
				(width 0.1524)
				(type default)
			)
			(layer "F.SilkS")
		)
		(fp_line
			(start -2.6289 3.4417)
			(end -2.6289 1.4732)
			(stroke
				(width 0.381)
				(type default)
			)
			(layer "F.SilkS")
		)
		(fp_line
			(start -2.1844 -0.0508)
			(end -2.7178 0.508)
			(stroke
				(width 0.1524)
				(type default)
			)
			(layer "F.SilkS")
		)
		(fp_line
			(start 2.1336 -1.4224)
			(end -2.7432 -1.4224)
			(stroke
				(width 0.1524)
				(type default)
			)
			(layer "F.SilkS")
		)
		(fp_line
			(start 2.1336 1.4224)
			(end 2.1336 -1.4224)
			(stroke
				(width 0.1524)
				(type default)
			)
			(layer "F.SilkS")
		)
		(fp_poly
			(pts
				(xy -2.2098 -1.4224) (xy -2.2098 1.4224) (xy 2.2098 1.4224) (xy 2.2098 -1.4224)
			)
			(stroke
				(width 0)
				(type default)
			)
			(fill yes)
			(layer "F.SilkS")
		)
		(fp_rect
			(start -2.450084 2.999994)
			(end 2.450084 -2.999994)
			(stroke
				(width 0)
				(type default)
			)
			(fill no)
			(layer "F.CrtYd")
		)
		(fp_poly
			(pts
				(xy -2.8194 3.6322) (xy -2.8194 -3.6322) (xy 2.8194 -3.6322) (xy 2.8194 1.18364) (xy 2.450084 1.18364)
				(xy 2.450084 -2.999994) (xy -2.450084 -2.999994) (xy -2.450084 2.999994) (xy 2.450084 2.999994)
				(xy 2.450084 1.18618) (xy 2.8194 1.18618) (xy 2.8194 3.6322)
			)
			(stroke
				(width 0)
				(type default)
			)
			(fill no)
			(layer "F.CrtYd")
		)
		(fp_rect
			(start -2.8194 3.6322)
			(end 2.8194 -3.6322)
			(stroke
				(width 0)
				(type default)
			)
			(fill no)
			(layer "F.Fab")
		)
		(pad "1" smd rect
			(at -1.905 2.54)
			(size 0.635 1.651)
			(layers "F.Cu" "F.Mask" "F.Paste")
			(net "P12V_B")
		)
		(pad "2" smd rect
			(at -0.635 2.54)
			(size 0.635 1.651)
			(layers "F.Cu" "F.Mask" "F.Paste")
			(net "P12V_B")
		)
		(pad "3" smd rect
			(at 0.635 2.54)
			(size 0.635 1.651)
			(layers "F.Cu" "F.Mask" "F.Paste")
			(net "P12V_B")
		)
		(pad "4" smd rect
			(at 1.905 2.54)
			(size 0.635 1.651)
			(layers "F.Cu" "F.Mask" "F.Paste")
			(net "SW_HDD_N10")
		)
		(pad "5" smd rect
			(at 1.905 -2.54)
			(size 0.635 1.651)
			(layers "F.Cu" "F.Mask" "F.Paste")
			(net "P12V_HDD10")
		)
		(pad "6" smd rect
			(at 0.635 -2.54)
			(size 0.635 1.651)
			(layers "F.Cu" "F.Mask" "F.Paste")
			(net "P12V_HDD10")
		)
		(pad "7" smd rect
			(at -0.635 -2.54)
			(size 0.635 1.651)
			(layers "F.Cu" "F.Mask" "F.Paste")
			(net "P12V_HDD10")
		)
		(pad "8" smd rect
			(at -1.905 -2.54)
			(size 0.635 1.651)
			(layers "F.Cu" "F.Mask" "F.Paste")
			(net "P12V_HDD10")
		)
	)
	(footprint ""
		(layer "F.Cu")
		(at 34.285682 -244.990874 90)
		(property "Reference" "VIA1"
			(at 0 0 90)
			(layer "F.SilkS")
			(hide yes)
			(effects
				(font
					(size 1.27 1.27)
				)
			)
		)
		(property "Value" "100OHM-8L-2D36MM-L18-GP"
			(at 3.8989 0.5715 90)
			(unlocked yes)
			(layer "F.Fab")
			(hide yes)
			(effects
				(font
					(size 1.016 1.016)
					(thickness 0.1524)
				)
			)
		)
		(property "Device Type" "VIA-PCIE-4P-414097"
			(at 3.8989 -0.9525 90)
			(unlocked yes)
			(layer "F.Fab")
			(hide yes)
			(effects
				(font
					(size 1.016 1.016)
					(thickness 0.1524)
				)
			)
		)
		(duplicate_pad_numbers_are_jumpers no)
		(fp_rect
			(start -2.0701 0.4826)
			(end 2.0701 -0.4826)
			(stroke
				(width 0)
				(type default)
			)
			(fill no)
			(layer "F.CrtYd")
		)
		(fp_rect
			(start -2.0701 0.4826)
			(end 2.0701 -0.4826)
			(stroke
				(width 0)
				(type default)
			)
			(fill no)
			(layer "F.Fab")
		)
		(pad "1" thru_hole circle
			(at -1.5875 0 90)
			(size 0.508 0.508)
			(drill 0.254)
			(layers "*.Cu" "*.Mask")
			(remove_unused_layers no)
			(net "GND")
			(clearance 0.2286)
			(thermal_gap 0.2286)
		)
		(pad "2" thru_hole circle
			(at -0.5715 0 90)
			(size 0.508 0.508)
			(drill 0.254)
			(layers "*.Cu" "*.Mask")
			(remove_unused_layers no)
			(net "PHY_SCC_B_TO_DRV_B_0_DP")
			(clearance 0.2286)
			(thermal_gap 0.2286)
		)
		(pad "3" thru_hole circle
			(at 0.5715 0 90)
			(size 0.508 0.508)
			(drill 0.254)
			(layers "*.Cu" "*.Mask")
			(remove_unused_layers no)
			(net "PHY_SCC_B_TO_DRV_B_0_DN")
			(clearance 0.2286)
			(thermal_gap 0.2286)
		)
		(pad "4" thru_hole circle
			(at 1.5875 0 90)
			(size 0.508 0.508)
			(drill 0.254)
			(layers "*.Cu" "*.Mask")
			(remove_unused_layers no)
			(net "GND")
			(clearance 0.2286)
			(thermal_gap 0.2286)
		)
	)
	(footprint ""
		(layer "F.Cu")
		(at 35.426396 -374.1166 -90)
		(property "Reference" "R925"
			(at 0 0 270)
			(layer "F.SilkS")
			(hide yes)
			(effects
				(font
					(size 1.27 1.27)
				)
			)
		)
		(property "Value" "0R2J-2-GP"
			(at 0.064008 -3.993896 270)
			(unlocked yes)
			(layer "F.Fab")
			(hide yes)
			(effects
				(font
					(size 1.016 1.016)
					(thickness 0.1524)
				)
			)
		)
		(property "Device Type" "R402H16"
			(at 0.064008 -5.517896 270)
			(unlocked yes)
			(layer "F.Fab")
			(hide yes)
			(effects
				(font
					(size 1.016 1.016)
					(thickness 0.1524)
				)
			)
		)
		(duplicate_pad_numbers_are_jumpers no)
		(fp_line
			(start -0.508 -0.9398)
			(end -0.508 0.9398)
			(stroke
				(width 0.1524)
				(type default)
			)
			(layer "F.SilkS")
		)
		(fp_line
			(start 0.508 -0.9398)
			(end -0.508 -0.9398)
			(stroke
				(width 0.1524)
				(type default)
			)
			(layer "F.SilkS")
		)
		(fp_rect
			(start -0.508 0.9398)
			(end 0.508 -0.9398)
			(stroke
				(width 0)
				(type default)
			)
			(fill no)
			(layer "F.CrtYd")
		)
		(fp_rect
			(start -0.508 0.9398)
			(end 0.508 -0.9398)
			(stroke
				(width 0)
				(type default)
			)
			(fill no)
			(layer "F.Fab")
		)
		(pad "1" smd custom
			(at 0 -0.4445 270)
			(size 0.1397 0.1397)
			(layers "F.Cu" "F.Mask" "F.Paste")
			(net "FAN_0_PWM")
			(options
				(clearance outline)
				(anchor circle)
			)
			(primitives
				(gr_poly
					(pts
						(arc
							(start -0.1778 -0.2794)
							(mid -0.249642 -0.249642)
							(end -0.2794 -0.1778)
						)
						(arc
							(start -0.2794 0.1778)
							(mid -0.249642 0.249642)
							(end -0.1778 0.2794)
						)
						(arc
							(start 0.1778 0.2794)
							(mid 0.249642 0.249642)
							(end 0.2794 0.1778)
						)
						(arc
							(start 0.2794 -0.1778)
							(mid 0.249642 -0.249642)
							(end 0.1778 -0.2794)
						)
					)
					(width 0)
					(fill yes)
				)
			)
		)
		(pad "2" smd custom
			(at 0 0.4445 270)
			(size 0.1397 0.1397)
			(layers "F.Cu" "F.Mask" "F.Paste")
			(net "PWM_OUT_FAN0")
			(options
				(clearance outline)
				(anchor circle)
			)
			(primitives
				(gr_poly
					(pts
						(arc
							(start -0.1778 -0.2794)
							(mid -0.249642 -0.249642)
							(end -0.2794 -0.1778)
						)
						(arc
							(start -0.2794 0.1778)
							(mid -0.249642 0.249642)
							(end -0.1778 0.2794)
						)
						(arc
							(start 0.1778 0.2794)
							(mid 0.249642 0.249642)
							(end 0.2794 0.1778)
						)
						(arc
							(start 0.2794 -0.1778)
							(mid 0.249642 -0.249642)
							(end 0.1778 -0.2794)
						)
					)
					(width 0)
					(fill yes)
				)
			)
		)
	)
	(footprint ""
		(layer "F.Cu")
		(at 415.3154 -261.6454 180)
		(property "Reference" "R303"
			(at 0 0 180)
			(layer "F.SilkS")
			(hide yes)
			(effects
				(font
					(size 1.27 1.27)
				)
			)
		)
		(property "Value" "10KR2F-2-GP"
			(at 0.064008 -3.993896 180)
			(unlocked yes)
			(layer "F.Fab")
			(hide yes)
			(effects
				(font
					(size 1.016 1.016)
					(thickness 0.1524)
				)
			)
		)
		(property "Device Type" "R402H16"
			(at 0.064008 -5.517896 180)
			(unlocked yes)
			(layer "F.Fab")
			(hide yes)
			(effects
				(font
					(size 1.016 1.016)
					(thickness 0.1524)
				)
			)
		)
		(duplicate_pad_numbers_are_jumpers no)
		(fp_line
			(start 0.508 -0.9398)
			(end -0.508 -0.9398)
			(stroke
				(width 0.1524)
				(type default)
			)
			(layer "F.SilkS")
		)
		(fp_line
			(start -0.508 -0.9398)
			(end -0.508 0.9398)
			(stroke
				(width 0.1524)
				(type default)
			)
			(layer "F.SilkS")
		)
		(fp_rect
			(start -0.508 0.9398)
			(end 0.508 -0.9398)
			(stroke
				(width 0)
				(type default)
			)
			(fill no)
			(layer "F.CrtYd")
		)
		(fp_rect
			(start -0.508 0.9398)
			(end 0.508 -0.9398)
			(stroke
				(width 0)
				(type default)
			)
			(fill no)
			(layer "F.Fab")
		)
		(pad "1" smd custom
			(at 0 -0.4445 180)
			(size 0.1397 0.1397)
			(layers "F.Cu" "F.Mask" "F.Paste")
			(net "P3V3_STBY_B")
			(options
				(clearance outline)
				(anchor circle)
			)
			(primitives
				(gr_poly
					(pts
						(arc
							(start -0.1778 -0.2794)
							(mid -0.249642 -0.249642)
							(end -0.2794 -0.1778)
						)
						(arc
							(start -0.2794 0.1778)
							(mid -0.249642 0.249642)
							(end -0.1778 0.2794)
						)
						(arc
							(start 0.1778 0.2794)
							(mid 0.249642 0.249642)
							(end 0.2794 0.1778)
						)
						(arc
							(start 0.2794 -0.1778)
							(mid 0.249642 -0.249642)
							(end 0.1778 -0.2794)
						)
					)
					(width 0)
					(fill yes)
				)
			)
		)
		(pad "2" smd custom
			(at 0 0.4445 180)
			(size 0.1397 0.1397)
			(layers "F.Cu" "F.Mask" "F.Paste")
			(net "HDD_PRSNT_9")
			(options
				(clearance outline)
				(anchor circle)
			)
			(primitives
				(gr_poly
					(pts
						(arc
							(start -0.1778 -0.2794)
							(mid -0.249642 -0.249642)
							(end -0.2794 -0.1778)
						)
						(arc
							(start -0.2794 0.1778)
							(mid -0.249642 0.249642)
							(end -0.1778 0.2794)
						)
						(arc
							(start 0.1778 0.2794)
							(mid 0.249642 0.249642)
							(end 0.2794 0.1778)
						)
						(arc
							(start 0.2794 -0.1778)
							(mid 0.249642 -0.249642)
							(end 0.1778 -0.2794)
						)
					)
					(width 0)
					(fill yes)
				)
			)
		)
	)
	(footprint ""
		(layer "F.Cu")
		(at 426.974 -151.892 180)
		(property "Reference" "C304"
			(at 0 0 180)
			(layer "F.SilkS")
			(hide yes)
			(effects
				(font
					(size 1.27 1.27)
				)
			)
		)
		(property "Value" "SC10U16V6KX-2GP"
			(at -0.0762 -5.1308 180)
			(unlocked yes)
			(layer "F.Fab")
			(hide yes)
			(effects
				(font
					(size 1.016 1.016)
					(thickness 0.1524)
				)
			)
		)
		(property "Device Type" "C1206H71"
			(at -0.127 -6.6548 180)
			(unlocked yes)
			(layer "F.Fab")
			(hide yes)
			(effects
				(font
					(size 1.016 1.016)
					(thickness 0.1524)
				)
			)
		)
		(duplicate_pad_numbers_are_jumpers no)
		(fp_line
			(start 1.016 2.2352)
			(end -1.016 2.2352)
			(stroke
				(width 0.1524)
				(type default)
			)
			(layer "F.SilkS")
		)
		(fp_line
			(start 1.016 0.8382)
			(end 1.016 2.2352)
			(stroke
				(width 0.1524)
				(type default)
			)
			(layer "F.SilkS")
		)
		(fp_line
			(start 1.016 -2.2352)
			(end 1.016 -0.8382)
			(stroke
				(width 0.1524)
				(type default)
			)
			(layer "F.SilkS")
		)
		(fp_line
			(start -1.016 2.2352)
			(end -1.016 0.8382)
			(stroke
				(width 0.1524)
				(type default)
			)
			(layer "F.SilkS")
		)
		(fp_line
			(start -1.016 -0.8382)
			(end -1.016 -2.2352)
			(stroke
				(width 0.1524)
				(type default)
			)
			(layer "F.SilkS")
		)
		(fp_line
			(start -1.016 -2.2352)
			(end 1.016 -2.2352)
			(stroke
				(width 0.1524)
				(type default)
			)
			(layer "F.SilkS")
		)
		(fp_rect
			(start -1.0922 2.3114)
			(end 1.0922 -2.3114)
			(stroke
				(width 0)
				(type default)
			)
			(fill no)
			(layer "F.CrtYd")
		)
		(fp_poly
			(pts
				(xy 1.0922 -2.3114) (xy 1.0922 2.3114) (xy -1.0922 2.3114) (xy -1.0922 -2.3114)
			)
			(stroke
				(width 0)
				(type default)
			)
			(fill no)
			(layer "F.Fab")
		)
		(pad "1" smd rect
			(at 0 -1.397 180)
			(size 1.651 1.27)
			(layers "F.Cu" "F.Mask" "F.Paste")
			(net "P5V_HDD21")
		)
		(pad "2" smd rect
			(at 0 1.397 180)
			(size 1.651 1.27)
			(layers "F.Cu" "F.Mask" "F.Paste")
			(net "GND")
		)
	)
	(footprint ""
		(layer "F.Cu")
		(at 209.804 -225.679 -90)
		(property "Reference" "R24"
			(at 0 0 270)
			(layer "F.SilkS")
			(hide yes)
			(effects
				(font
					(size 1.27 1.27)
				)
			)
		)
		(property "Value" "4K7R2F-GP"
			(at 0.064008 -3.993896 270)
			(unlocked yes)
			(layer "F.Fab")
			(hide yes)
			(effects
				(font
					(size 1.016 1.016)
					(thickness 0.1524)
				)
			)
		)
		(property "Device Type" "R402H16"
			(at 0.064008 -5.517896 270)
			(unlocked yes)
			(layer "F.Fab")
			(hide yes)
			(effects
				(font
					(size 1.016 1.016)
					(thickness 0.1524)
				)
			)
		)
		(duplicate_pad_numbers_are_jumpers no)
		(fp_line
			(start -0.508 -0.9398)
			(end -0.508 0.9398)
			(stroke
				(width 0.1524)
				(type default)
			)
			(layer "F.SilkS")
		)
		(fp_line
			(start 0.508 -0.9398)
			(end -0.508 -0.9398)
			(stroke
				(width 0.1524)
				(type default)
			)
			(layer "F.SilkS")
		)
		(fp_rect
			(start -0.508 0.9398)
			(end 0.508 -0.9398)
			(stroke
				(width 0)
				(type default)
			)
			(fill no)
			(layer "F.CrtYd")
		)
		(fp_rect
			(start -0.508 0.9398)
			(end 0.508 -0.9398)
			(stroke
				(width 0)
				(type default)
			)
			(fill no)
			(layer "F.Fab")
		)
		(pad "1" smd custom
			(at 0 -0.4445 270)
			(size 0.1397 0.1397)
			(layers "F.Cu" "F.Mask" "F.Paste")
			(net "IO_EXP1_HDD_FAULT_A1")
			(options
				(clearance outline)
				(anchor circle)
			)
			(primitives
				(gr_poly
					(pts
						(arc
							(start -0.1778 -0.2794)
							(mid -0.249642 -0.249642)
							(end -0.2794 -0.1778)
						)
						(arc
							(start -0.2794 0.1778)
							(mid -0.249642 0.249642)
							(end -0.1778 0.2794)
						)
						(arc
							(start 0.1778 0.2794)
							(mid 0.249642 0.249642)
							(end 0.2794 0.1778)
						)
						(arc
							(start 0.2794 -0.1778)
							(mid 0.249642 -0.249642)
							(end 0.1778 -0.2794)
						)
					)
					(width 0)
					(fill yes)
				)
			)
		)
		(pad "2" smd custom
			(at 0 0.4445 270)
			(size 0.1397 0.1397)
			(layers "F.Cu" "F.Mask" "F.Paste")
			(net "GND")
			(options
				(clearance outline)
				(anchor circle)
			)
			(primitives
				(gr_poly
					(pts
						(arc
							(start -0.1778 -0.2794)
							(mid -0.249642 -0.249642)
							(end -0.2794 -0.1778)
						)
						(arc
							(start -0.2794 0.1778)
							(mid -0.249642 0.249642)
							(end -0.1778 0.2794)
						)
						(arc
							(start 0.1778 0.2794)
							(mid 0.249642 0.249642)
							(end 0.2794 0.1778)
						)
						(arc
							(start 0.2794 -0.1778)
							(mid 0.249642 -0.249642)
							(end 0.1778 -0.2794)
						)
					)
					(width 0)
					(fill yes)
				)
			)
		)
	)
	(footprint ""
		(layer "F.Cu")
		(at 457.9874 -19.5072 180)
		(property "Reference" "C480"
			(at 0 0 180)
			(layer "F.SilkS")
			(hide yes)
			(effects
				(font
					(size 1.27 1.27)
				)
			)
		)
		(property "Value" "SCD033U25V2KX-GP"
			(at 1.1811 -2.7051 180)
			(unlocked yes)
			(layer "F.Fab")
			(hide yes)
			(effects
				(font
					(size 1.016 1.016)
					(thickness 0.1524)
				)
			)
		)
		(property "Device Type" "C402H22"
			(at 1.1811 -4.2291 180)
			(unlocked yes)
			(layer "F.Fab")
			(hide yes)
			(effects
				(font
					(size 1.016 1.016)
					(thickness 0.1524)
				)
			)
		)
		(duplicate_pad_numbers_are_jumpers no)
		(fp_rect
			(start -0.4318 0.9525)
			(end 0.4318 -0.9525)
			(stroke
				(width 0)
				(type default)
			)
			(fill no)
			(layer "F.CrtYd")
		)
		(fp_rect
			(start -0.4318 0.9525)
			(end 0.4318 -0.9525)
			(stroke
				(width 0)
				(type default)
			)
			(fill no)
			(layer "F.Fab")
		)
		(pad "1" smd custom
			(at 0 -0.4445 180)
			(size 0.1524 0.1524)
			(layers "F.Cu" "F.Mask" "F.Paste")
			(net "SW_HDD_P34")
			(options
				(clearance outline)
				(anchor circle)
			)
			(primitives
				(gr_poly
					(pts
						(arc
							(start 0.3048 -0.2032)
							(mid 0.275042 -0.275042)
							(end 0.2032 -0.3048)
						)
						(arc
							(start -0.2032 -0.3048)
							(mid -0.275042 -0.275042)
							(end -0.3048 -0.2032)
						)
						(arc
							(start -0.3048 0.2032)
							(mid -0.275042 0.275042)
							(end -0.2032 0.3048)
						)
						(arc
							(start 0.2032 0.3048)
							(mid 0.275042 0.275042)
							(end 0.3048 0.2032)
						)
					)
					(width 0)
					(fill yes)
				)
			)
		)
		(pad "2" smd custom
			(at 0 0.4445 180)
			(size 0.1524 0.1524)
			(layers "F.Cu" "F.Mask" "F.Paste")
			(net "GND")
			(options
				(clearance outline)
				(anchor circle)
			)
			(primitives
				(gr_poly
					(pts
						(arc
							(start 0.3048 -0.2032)
							(mid 0.275042 -0.275042)
							(end 0.2032 -0.3048)
						)
						(arc
							(start -0.2032 -0.3048)
							(mid -0.275042 -0.275042)
							(end -0.3048 -0.2032)
						)
						(arc
							(start -0.3048 0.2032)
							(mid -0.275042 0.275042)
							(end -0.2032 0.3048)
						)
						(arc
							(start 0.2032 0.3048)
							(mid 0.275042 0.275042)
							(end 0.3048 0.2032)
						)
					)
					(width 0)
					(fill yes)
				)
			)
		)
	)
)
